(kicad_pcb
	(version 20260206)
	(generator "pcbnew")
	(generator_version "10.0")
	(general
		(thickness 1.6)
		(legacy_teardrops no)
	)
	(paper "A4")
	(title_block
		(title "Bryce Canyon_R.DPB_16317-1_OCP.brd")
		(comment 1 "Bryce Canyon / footprints 1817-1823 of 2099")
	)
	(layers
		(0 "F.Cu" signal "TOP")
		(4 "In1.Cu" signal "L2GND")
		(6 "In2.Cu" signal "L3")
		(8 "In3.Cu" signal "L4VCC")
		(10 "In4.Cu" signal "L5VCC")
		(12 "In5.Cu" signal "L6")
		(14 "In6.Cu" signal "L7GND")
		(2 "B.Cu" signal "BOTTOM")
		(9 "F.Adhes" user "F.Adhesive")
		(11 "B.Adhes" user "B.Adhesive")
		(13 "F.Paste" user "Package Geometry/Pastemask Top")
		(15 "B.Paste" user "Package Geometry/Pastemask Bottom")
		(5 "F.SilkS" user "Ref Des/Silkscreen Top")
		(7 "B.SilkS" user "Ref Des/Silkscreen Bottom")
		(1 "F.Mask" user "Board Geometry/Soldermask Top")
		(3 "B.Mask" user "Board Geometry/Soldermask Bottom")
		(17 "Dwgs.User" user "User.Drawings")
		(19 "Cmts.User" user "User.Comments")
		(21 "Eco1.User" user "User.Eco1")
		(23 "Eco2.User" user "User.Eco2")
		(25 "Edge.Cuts" user "Board Geometry/Outline")
		(27 "Margin" user)
		(31 "F.CrtYd" user "Package Geometry/Place Bound Top")
		(29 "B.CrtYd" user "Package Geometry/Place Bound Bottom")
		(35 "F.Fab" user "Ref Des/Assembly Top")
		(33 "B.Fab" user "Ref Des/Assembly Bottom")
	)
	(footprint ""
		(layer "F.Cu")
		(at 329.819 -37.846 180)
		(property "Reference" "C420"
			(at 0 0 180)
			(layer "F.SilkS")
			(hide yes)
			(effects
				(font
					(size 1.27 1.27)
				)
			)
		)
		(property "Value" "SC1U16V3KX-5GP"
			(at 0 -2.8194 180)
			(unlocked yes)
			(layer "F.Fab")
			(hide yes)
			(effects
				(font
					(size 1.016 1.016)
					(thickness 0.1524)
				)
			)
		)
		(property "Device Type" "C603H36"
			(at 0 -4.3434 180)
			(unlocked yes)
			(layer "F.Fab")
			(hide yes)
			(effects
				(font
					(size 1.016 1.016)
					(thickness 0.1524)
				)
			)
		)
		(duplicate_pad_numbers_are_jumpers no)
		(fp_line
			(start 0.508 0)
			(end -0.508 0)
			(stroke
				(width 0.2032)
				(type default)
			)
			(layer "F.SilkS")
		)
		(fp_rect
			(start -0.5842 1.3335)
			(end 0.5842 -1.3335)
			(stroke
				(width 0)
				(type default)
			)
			(fill no)
			(layer "F.CrtYd")
		)
		(fp_rect
			(start -0.5842 1.3335)
			(end 0.5842 -1.3335)
			(stroke
				(width 0)
				(type default)
			)
			(fill no)
			(layer "F.Fab")
		)
		(pad "1" smd custom
			(at 0 -0.762 180)
			(size 0.2159 0.2159)
			(layers "F.Cu" "F.Mask" "F.Paste")
			(net "P5V_HDD30")
			(options
				(clearance outline)
				(anchor circle)
			)
			(primitives
				(gr_poly
					(pts
						(arc
							(start -0.3302 -0.4318)
							(mid -0.402042 -0.402042)
							(end -0.4318 -0.3302)
						)
						(arc
							(start -0.4318 0.3302)
							(mid -0.402042 0.402042)
							(end -0.3302 0.4318)
						)
						(arc
							(start 0.3302 0.4318)
							(mid 0.402042 0.402042)
							(end 0.4318 0.3302)
						)
						(arc
							(start 0.4318 -0.3302)
							(mid 0.402042 -0.402042)
							(end 0.3302 -0.4318)
						)
					)
					(width 0)
					(fill yes)
				)
			)
		)
		(pad "2" smd custom
			(at 0 0.762 180)
			(size 0.2159 0.2159)
			(layers "F.Cu" "F.Mask" "F.Paste")
			(net "GND")
			(options
				(clearance outline)
				(anchor circle)
			)
			(primitives
				(gr_poly
					(pts
						(arc
							(start -0.3302 -0.4318)
							(mid -0.402042 -0.402042)
							(end -0.4318 -0.3302)
						)
						(arc
							(start -0.4318 0.3302)
							(mid -0.402042 0.402042)
							(end -0.3302 0.4318)
						)
						(arc
							(start 0.3302 0.4318)
							(mid 0.402042 0.402042)
							(end 0.4318 0.3302)
						)
						(arc
							(start 0.4318 -0.3302)
							(mid 0.402042 -0.402042)
							(end 0.3302 -0.4318)
						)
					)
					(width 0)
					(fill yes)
				)
			)
		)
	)
	(footprint ""
		(layer "F.Cu")
		(at 248.285 -307.086 90)
		(property "Reference" "R1090"
			(at 0 0 90)
			(layer "F.SilkS")
			(hide yes)
			(effects
				(font
					(size 1.27 1.27)
				)
			)
		)
		(property "Value" "0R2J-2-GP"
			(at 0.064008 -3.993896 90)
			(unlocked yes)
			(layer "F.Fab")
			(hide yes)
			(effects
				(font
					(size 1.016 1.016)
					(thickness 0.1524)
				)
			)
		)
		(property "Device Type" "R402H16"
			(at 0.064008 -5.517896 90)
			(unlocked yes)
			(layer "F.Fab")
			(hide yes)
			(effects
				(font
					(size 1.016 1.016)
					(thickness 0.1524)
				)
			)
		)
		(duplicate_pad_numbers_are_jumpers no)
		(fp_line
			(start 0.508 -0.9398)
			(end -0.508 -0.9398)
			(stroke
				(width 0.1524)
				(type default)
			)
			(layer "F.SilkS")
		)
		(fp_line
			(start -0.508 -0.9398)
			(end -0.508 0.9398)
			(stroke
				(width 0.1524)
				(type default)
			)
			(layer "F.SilkS")
		)
		(fp_rect
			(start -0.508 0.9398)
			(end 0.508 -0.9398)
			(stroke
				(width 0)
				(type default)
			)
			(fill no)
			(layer "F.CrtYd")
		)
		(fp_rect
			(start -0.508 0.9398)
			(end 0.508 -0.9398)
			(stroke
				(width 0)
				(type default)
			)
			(fill no)
			(layer "F.Fab")
		)
		(pad "1" smd custom
			(at 0 -0.4445 90)
			(size 0.1397 0.1397)
			(layers "F.Cu" "F.Mask" "F.Paste")
			(net "MAX31790_A_PWM_ST0")
			(options
				(clearance outline)
				(anchor circle)
			)
			(primitives
				(gr_poly
					(pts
						(arc
							(start -0.1778 -0.2794)
							(mid -0.249642 -0.249642)
							(end -0.2794 -0.1778)
						)
						(arc
							(start -0.2794 0.1778)
							(mid -0.249642 0.249642)
							(end -0.1778 0.2794)
						)
						(arc
							(start 0.1778 0.2794)
							(mid 0.249642 0.249642)
							(end 0.2794 0.1778)
						)
						(arc
							(start 0.2794 -0.1778)
							(mid 0.249642 -0.249642)
							(end 0.1778 -0.2794)
						)
					)
					(width 0)
					(fill yes)
				)
			)
		)
		(pad "2" smd custom
			(at 0 0.4445 90)
			(size 0.1397 0.1397)
			(layers "F.Cu" "F.Mask" "F.Paste")
			(net "GND")
			(options
				(clearance outline)
				(anchor circle)
			)
			(primitives
				(gr_poly
					(pts
						(arc
							(start -0.1778 -0.2794)
							(mid -0.249642 -0.249642)
							(end -0.2794 -0.1778)
						)
						(arc
							(start -0.2794 0.1778)
							(mid -0.249642 0.249642)
							(end -0.1778 0.2794)
						)
						(arc
							(start 0.1778 0.2794)
							(mid 0.249642 0.249642)
							(end 0.2794 0.1778)
						)
						(arc
							(start 0.2794 -0.1778)
							(mid 0.249642 -0.249642)
							(end 0.1778 -0.2794)
						)
					)
					(width 0)
					(fill yes)
				)
			)
		)
	)
	(footprint ""
		(layer "F.Cu")
		(at 433.324 -258.826 90)
		(property "Reference" "C156"
			(at 0 0 90)
			(layer "F.SilkS")
			(hide yes)
			(effects
				(font
					(size 1.27 1.27)
				)
			)
		)
		(property "Value" "SCD033U25V2KX-GP"
			(at 1.1811 -2.7051 90)
			(unlocked yes)
			(layer "F.Fab")
			(hide yes)
			(effects
				(font
					(size 1.016 1.016)
					(thickness 0.1524)
				)
			)
		)
		(property "Device Type" "C402H22"
			(at 1.1811 -4.2291 90)
			(unlocked yes)
			(layer "F.Fab")
			(hide yes)
			(effects
				(font
					(size 1.016 1.016)
					(thickness 0.1524)
				)
			)
		)
		(duplicate_pad_numbers_are_jumpers no)
		(fp_rect
			(start -0.4318 0.9525)
			(end 0.4318 -0.9525)
			(stroke
				(width 0)
				(type default)
			)
			(fill no)
			(layer "F.CrtYd")
		)
		(fp_rect
			(start -0.4318 0.9525)
			(end 0.4318 -0.9525)
			(stroke
				(width 0)
				(type default)
			)
			(fill no)
			(layer "F.Fab")
		)
		(pad "1" smd custom
			(at 0 -0.4445 90)
			(size 0.1524 0.1524)
			(layers "F.Cu" "F.Mask" "F.Paste")
			(net "P12V_B")
			(options
				(clearance outline)
				(anchor circle)
			)
			(primitives
				(gr_poly
					(pts
						(arc
							(start 0.3048 -0.2032)
							(mid 0.275042 -0.275042)
							(end 0.2032 -0.3048)
						)
						(arc
							(start -0.2032 -0.3048)
							(mid -0.275042 -0.275042)
							(end -0.3048 -0.2032)
						)
						(arc
							(start -0.3048 0.2032)
							(mid -0.275042 0.275042)
							(end -0.2032 0.3048)
						)
						(arc
							(start 0.2032 0.3048)
							(mid 0.275042 0.275042)
							(end 0.3048 0.2032)
						)
					)
					(width 0)
					(fill yes)
				)
			)
		)
		(pad "2" smd custom
			(at 0 0.4445 90)
			(size 0.1524 0.1524)
			(layers "F.Cu" "F.Mask" "F.Paste")
			(net "SW_HDD_N9")
			(options
				(clearance outline)
				(anchor circle)
			)
			(primitives
				(gr_poly
					(pts
						(arc
							(start 0.3048 -0.2032)
							(mid 0.275042 -0.275042)
							(end 0.2032 -0.3048)
						)
						(arc
							(start -0.2032 -0.3048)
							(mid -0.275042 -0.275042)
							(end -0.3048 -0.2032)
						)
						(arc
							(start -0.3048 0.2032)
							(mid -0.275042 0.275042)
							(end -0.2032 0.3048)
						)
						(arc
							(start 0.2032 0.3048)
							(mid 0.275042 0.275042)
							(end 0.3048 0.2032)
						)
					)
					(width 0)
					(fill yes)
				)
			)
		)
	)
	(footprint ""
		(layer "F.Cu")
		(at 440.931554 -118.03507 -90)
		(property "Reference" "R1161"
			(at 0 0 270)
			(layer "F.SilkS")
			(hide yes)
			(effects
				(font
					(size 1.27 1.27)
				)
			)
		)
		(property "Value" "15KR2F-GP"
			(at 0.064008 -3.993896 270)
			(unlocked yes)
			(layer "F.Fab")
			(hide yes)
			(effects
				(font
					(size 1.016 1.016)
					(thickness 0.1524)
				)
			)
		)
		(property "Device Type" "R402H16"
			(at 0.064008 -5.517896 270)
			(unlocked yes)
			(layer "F.Fab")
			(hide yes)
			(effects
				(font
					(size 1.016 1.016)
					(thickness 0.1524)
				)
			)
		)
		(duplicate_pad_numbers_are_jumpers no)
		(fp_line
			(start -0.508 -0.9398)
			(end -0.508 0.9398)
			(stroke
				(width 0.1524)
				(type default)
			)
			(layer "F.SilkS")
		)
		(fp_line
			(start 0.508 -0.9398)
			(end -0.508 -0.9398)
			(stroke
				(width 0.1524)
				(type default)
			)
			(layer "F.SilkS")
		)
		(fp_rect
			(start -0.508 0.9398)
			(end 0.508 -0.9398)
			(stroke
				(width 0)
				(type default)
			)
			(fill no)
			(layer "F.CrtYd")
		)
		(fp_rect
			(start -0.508 0.9398)
			(end 0.508 -0.9398)
			(stroke
				(width 0)
				(type default)
			)
			(fill no)
			(layer "F.Fab")
		)
		(pad "1" smd custom
			(at 0 -0.4445 270)
			(size 0.1397 0.1397)
			(layers "F.Cu" "F.Mask" "F.Paste")
			(net "P5V_B_4_PGOOD")
			(options
				(clearance outline)
				(anchor circle)
			)
			(primitives
				(gr_poly
					(pts
						(arc
							(start -0.1778 -0.2794)
							(mid -0.249642 -0.249642)
							(end -0.2794 -0.1778)
						)
						(arc
							(start -0.2794 0.1778)
							(mid -0.249642 0.249642)
							(end -0.1778 0.2794)
						)
						(arc
							(start 0.1778 0.2794)
							(mid 0.249642 0.249642)
							(end 0.2794 0.1778)
						)
						(arc
							(start 0.2794 -0.1778)
							(mid 0.249642 -0.249642)
							(end 0.1778 -0.2794)
						)
					)
					(width 0)
					(fill yes)
				)
			)
		)
		(pad "2" smd custom
			(at 0 0.4445 270)
			(size 0.1397 0.1397)
			(layers "F.Cu" "F.Mask" "F.Paste")
			(net "GND")
			(options
				(clearance outline)
				(anchor circle)
			)
			(primitives
				(gr_poly
					(pts
						(arc
							(start -0.1778 -0.2794)
							(mid -0.249642 -0.249642)
							(end -0.2794 -0.1778)
						)
						(arc
							(start -0.2794 0.1778)
							(mid -0.249642 0.249642)
							(end -0.1778 0.2794)
						)
						(arc
							(start 0.1778 0.2794)
							(mid 0.249642 0.249642)
							(end 0.2794 0.1778)
						)
						(arc
							(start 0.2794 -0.1778)
							(mid 0.249642 -0.249642)
							(end 0.1778 -0.2794)
						)
					)
					(width 0)
					(fill yes)
				)
			)
		)
	)
	(footprint ""
		(layer "F.Cu")
		(at 244.37848 -194.43954 -90)
		(property "Reference" "R78"
			(at 0 0 270)
			(layer "F.SilkS")
			(hide yes)
			(effects
				(font
					(size 1.27 1.27)
				)
			)
		)
		(property "Value" "4K7R2F-GP"
			(at 0.064008 -3.993896 270)
			(unlocked yes)
			(layer "F.Fab")
			(hide yes)
			(effects
				(font
					(size 1.016 1.016)
					(thickness 0.1524)
				)
			)
		)
		(property "Device Type" "R402H16"
			(at 0.064008 -5.517896 270)
			(unlocked yes)
			(layer "F.Fab")
			(hide yes)
			(effects
				(font
					(size 1.016 1.016)
					(thickness 0.1524)
				)
			)
		)
		(duplicate_pad_numbers_are_jumpers no)
		(fp_line
			(start -0.508 -0.9398)
			(end -0.508 0.9398)
			(stroke
				(width 0.1524)
				(type default)
			)
			(layer "F.SilkS")
		)
		(fp_line
			(start 0.508 -0.9398)
			(end -0.508 -0.9398)
			(stroke
				(width 0.1524)
				(type default)
			)
			(layer "F.SilkS")
		)
		(fp_rect
			(start -0.508 0.9398)
			(end 0.508 -0.9398)
			(stroke
				(width 0)
				(type default)
			)
			(fill no)
			(layer "F.CrtYd")
		)
		(fp_rect
			(start -0.508 0.9398)
			(end 0.508 -0.9398)
			(stroke
				(width 0)
				(type default)
			)
			(fill no)
			(layer "F.Fab")
		)
		(pad "1" smd custom
			(at 0 -0.4445 270)
			(size 0.1397 0.1397)
			(layers "F.Cu" "F.Mask" "F.Paste")
			(net "P3V3_STBY_B")
			(options
				(clearance outline)
				(anchor circle)
			)
			(primitives
				(gr_poly
					(pts
						(arc
							(start -0.1778 -0.2794)
							(mid -0.249642 -0.249642)
							(end -0.2794 -0.1778)
						)
						(arc
							(start -0.2794 0.1778)
							(mid -0.249642 0.249642)
							(end -0.1778 0.2794)
						)
						(arc
							(start 0.1778 0.2794)
							(mid 0.249642 0.249642)
							(end 0.2794 0.1778)
						)
						(arc
							(start 0.2794 -0.1778)
							(mid 0.249642 -0.249642)
							(end 0.1778 -0.2794)
						)
					)
					(width 0)
					(fill yes)
				)
			)
		)
		(pad "2" smd custom
			(at 0 0.4445 270)
			(size 0.1397 0.1397)
			(layers "F.Cu" "F.Mask" "F.Paste")
			(net "IO_EXP2_A1")
			(options
				(clearance outline)
				(anchor circle)
			)
			(primitives
				(gr_poly
					(pts
						(arc
							(start -0.1778 -0.2794)
							(mid -0.249642 -0.249642)
							(end -0.2794 -0.1778)
						)
						(arc
							(start -0.2794 0.1778)
							(mid -0.249642 0.249642)
							(end -0.1778 0.2794)
						)
						(arc
							(start 0.1778 0.2794)
							(mid 0.249642 0.249642)
							(end 0.2794 0.1778)
						)
						(arc
							(start 0.2794 -0.1778)
							(mid 0.249642 -0.249642)
							(end 0.1778 -0.2794)
						)
					)
					(width 0)
					(fill yes)
				)
			)
		)
	)
	(footprint ""
		(layer "F.Cu")
		(at 225.749104 -353.288854 180)
		(property "Reference" "C514"
			(at 0 0 180)
			(layer "F.SilkS")
			(hide yes)
			(effects
				(font
					(size 1.27 1.27)
				)
			)
		)
		(property "Value" "SC22U25V6KX-2-GP-U"
			(at -2.860802 -5.279644 180)
			(unlocked yes)
			(layer "F.Fab")
			(hide yes)
			(effects
				(font
					(size 1.016 1.016)
					(thickness 0.1524)
				)
			)
		)
		(property "Device Type" "C1206-TO0D3H75"
			(at -2.860802 -6.803644 180)
			(unlocked yes)
			(layer "F.Fab")
			(hide yes)
			(effects
				(font
					(size 1.016 1.016)
					(thickness 0.1524)
				)
			)
		)
		(duplicate_pad_numbers_are_jumpers no)
		(fp_line
			(start 1.3081 2.3749)
			(end -1.3081 2.3749)
			(stroke
				(width 0.1524)
				(type default)
			)
			(layer "F.SilkS")
		)
		(fp_line
			(start 1.3081 -2.3749)
			(end 1.3081 2.3749)
			(stroke
				(width 0.1524)
				(type default)
			)
			(layer "F.SilkS")
		)
		(fp_line
			(start -1.3081 2.3749)
			(end -1.3081 -2.3749)
			(stroke
				(width 0.1524)
				(type default)
			)
			(layer "F.SilkS")
		)
		(fp_line
			(start -1.3081 -2.3749)
			(end 1.3081 -2.3749)
			(stroke
				(width 0.1524)
				(type default)
			)
			(layer "F.SilkS")
		)
		(fp_rect
			(start -0.8001 1.6002)
			(end 0.8001 -1.6002)
			(stroke
				(width 0)
				(type default)
			)
			(fill no)
			(layer "F.CrtYd")
		)
		(fp_poly
			(pts
				(xy -1.5621 2.4511) (xy -1.5621 1.6002) (xy 0.8001 1.6002) (xy 0.8001 -1.6002) (xy -0.8001 -1.6002)
				(xy -0.8001 1.5875) (xy -1.5621 1.5875) (xy -1.5621 -2.4511) (xy 1.5621 -2.4511) (xy 1.5621 2.4511)
			)
			(stroke
				(width 0)
				(type default)
			)
			(fill no)
			(layer "F.CrtYd")
		)
		(fp_rect
			(start -1.5621 2.4511)
			(end 1.5621 -2.4511)
			(stroke
				(width 0)
				(type default)
			)
			(fill no)
			(layer "F.Fab")
		)
		(pad "1" smd rect
			(at 0 -1.392936 180)
			(size 2.1082 1.4478)
			(layers "F.Cu" "F.Mask" "F.Paste")
			(net "P12V_IN")
		)
		(pad "2" smd rect
			(at 0 1.392936 180)
			(size 2.1082 1.4478)
			(layers "F.Cu" "F.Mask" "F.Paste")
			(net "GND")
		)
	)
	(footprint ""
		(layer "F.Cu")
		(at 234.696 -224.409 180)
		(property "Reference" "C14"
			(at 0 0 180)
			(layer "F.SilkS")
			(hide yes)
			(effects
				(font
					(size 1.27 1.27)
				)
			)
		)
		(property "Value" "SCD1U16V2KX-3GP"
			(at 1.1811 -2.7051 180)
			(unlocked yes)
			(layer "F.Fab")
			(hide yes)
			(effects
				(font
					(size 1.016 1.016)
					(thickness 0.1524)
				)
			)
		)
		(property "Device Type" "C402H22"
			(at 1.1811 -4.2291 180)
			(unlocked yes)
			(layer "F.Fab")
			(hide yes)
			(effects
				(font
					(size 1.016 1.016)
					(thickness 0.1524)
				)
			)
		)
		(duplicate_pad_numbers_are_jumpers no)
		(fp_rect
			(start -0.4318 0.9525)
			(end 0.4318 -0.9525)
			(stroke
				(width 0)
				(type default)
			)
			(fill no)
			(layer "F.CrtYd")
		)
		(fp_rect
			(start -0.4318 0.9525)
			(end 0.4318 -0.9525)
			(stroke
				(width 0)
				(type default)
			)
			(fill no)
			(layer "F.Fab")
		)
		(pad "1" smd custom
			(at 0 -0.4445 180)
			(size 0.1524 0.1524)
			(layers "F.Cu" "F.Mask" "F.Paste")
			(net "GPIO_VCC_U8")
			(options
				(clearance outline)
				(anchor circle)
			)
			(primitives
				(gr_poly
					(pts
						(arc
							(start 0.3048 -0.2032)
							(mid 0.275042 -0.275042)
							(end 0.2032 -0.3048)
						)
						(arc
							(start -0.2032 -0.3048)
							(mid -0.275042 -0.275042)
							(end -0.3048 -0.2032)
						)
						(arc
							(start -0.3048 0.2032)
							(mid -0.275042 0.275042)
							(end -0.2032 0.3048)
						)
						(arc
							(start 0.2032 0.3048)
							(mid 0.275042 0.275042)
							(end 0.3048 0.2032)
						)
					)
					(width 0)
					(fill yes)
				)
			)
		)
		(pad "2" smd custom
			(at 0 0.4445 180)
			(size 0.1524 0.1524)
			(layers "F.Cu" "F.Mask" "F.Paste")
			(net "GND")
			(options
				(clearance outline)
				(anchor circle)
			)
			(primitives
				(gr_poly
					(pts
						(arc
							(start 0.3048 -0.2032)
							(mid 0.275042 -0.275042)
							(end 0.2032 -0.3048)
						)
						(arc
							(start -0.2032 -0.3048)
							(mid -0.275042 -0.275042)
							(end -0.3048 -0.2032)
						)
						(arc
							(start -0.3048 0.2032)
							(mid -0.275042 0.275042)
							(end -0.2032 0.3048)
						)
						(arc
							(start 0.2032 0.3048)
							(mid 0.275042 0.275042)
							(end 0.3048 0.2032)
						)
					)
					(width 0)
					(fill yes)
				)
			)
		)
	)
)
